(kicad_pcb
	(version 20260206)
	(generator "pcbnew")
	(generator_version "10.0")
	(general
		(thickness 1.6)
		(legacy_teardrops no)
	)
	(paper "A4")
	(title_block
		(title "baseboard — 13948-1b.1110WZS1818.brd")
		(comment 1 "Honey Badger (Wiwynn) / footprints 1254-1260 of 2523")
	)
	(layers
		(0 "F.Cu" signal "TOP")
		(4 "In1.Cu" signal "L2GND")
		(6 "In2.Cu" signal "L3")
		(8 "In3.Cu" signal "L4VCC")
		(10 "In4.Cu" signal "L5VCC")
		(12 "In5.Cu" signal "L6")
		(14 "In6.Cu" signal "L7GND")
		(2 "B.Cu" signal "BOTTOM")
		(9 "F.Adhes" user "F.Adhesive")
		(11 "B.Adhes" user "B.Adhesive")
		(13 "F.Paste" user "Package Geometry/Pastemask Top")
		(15 "B.Paste" user "Package Geometry/Pastemask Bottom")
		(5 "F.SilkS" user "Ref Des/Silkscreen Top")
		(7 "B.SilkS" user "Ref Des/Silkscreen Bottom")
		(1 "F.Mask" user "Board Geometry/Soldermask Top")
		(3 "B.Mask" user "Board Geometry/Soldermask Bottom")
		(17 "Dwgs.User" user "User.Drawings")
		(19 "Cmts.User" user "User.Comments")
		(21 "Eco1.User" user "User.Eco1")
		(23 "Eco2.User" user "User.Eco2")
		(25 "Edge.Cuts" user "Board Geometry/Outline")
		(27 "Margin" user)
		(31 "F.CrtYd" user "Package Geometry/Place Bound Top")
		(29 "B.CrtYd" user "Package Geometry/Place Bound Bottom")
		(35 "F.Fab" user "Ref Des/Assembly Top")
		(33 "B.Fab" user "Ref Des/Assembly Bottom")
	)
	(footprint ""
		(layer "F.Cu")
		(at 131.897882 -81.147158)
		(property "Reference" "SC1092"
			(at 0 0 0)
			(layer "F.SilkS")
			(hide yes)
			(effects
				(font
					(size 1.27 1.27)
				)
			)
		)
		(property "Value" "SCD01U10V1KX-GP"
			(at -2.8321 -1.7399 0)
			(unlocked yes)
			(layer "F.Fab")
			(hide yes)
			(effects
				(font
					(size 1.016 1.016)
					(thickness 0.1524)
				)
			)
		)
		(property "Device Type" "C0201H13"
			(at -2.8321 -3.2639 0)
			(unlocked yes)
			(layer "F.Fab")
			(hide yes)
			(effects
				(font
					(size 1.016 1.016)
					(thickness 0.1524)
				)
			)
		)
		(duplicate_pad_numbers_are_jumpers no)
		(fp_rect
			(start -0.2794 0.6477)
			(end 0.2794 -0.6477)
			(stroke
				(width 0)
				(type default)
			)
			(fill no)
			(layer "F.CrtYd")
		)
		(fp_rect
			(start -0.2794 0.6477)
			(end 0.2794 -0.6477)
			(stroke
				(width 0)
				(type default)
			)
			(fill no)
			(layer "F.Fab")
		)
		(pad "1" smd custom
			(at 0 -0.2794)
			(size 0.0762 0.0762)
			(layers "F.Cu" "F.Mask" "F.Paste")
			(net "SAS_HDD_TX12_P")
			(options
				(clearance outline)
				(anchor circle)
			)
			(primitives
				(gr_poly
					(pts
						(arc
							(start 0.1524 -0.127)
							(mid 0.137521 -0.162921)
							(end 0.1016 -0.1778)
						)
						(arc
							(start -0.1016 -0.1778)
							(mid -0.137521 -0.162921)
							(end -0.1524 -0.127)
						)
						(arc
							(start -0.1524 0.127)
							(mid -0.137521 0.162921)
							(end -0.1016 0.1778)
						)
						(arc
							(start 0.1016 0.1778)
							(mid 0.137521 0.162921)
							(end 0.1524 0.127)
						)
					)
					(width 0)
					(fill yes)
				)
			)
		)
		(pad "2" smd custom
			(at 0 0.2794)
			(size 0.0762 0.0762)
			(layers "F.Cu" "F.Mask" "F.Paste")
			(net "3008_SAS_RX_P0")
			(options
				(clearance outline)
				(anchor circle)
			)
			(primitives
				(gr_poly
					(pts
						(arc
							(start 0.1524 -0.127)
							(mid 0.137521 -0.162921)
							(end 0.1016 -0.1778)
						)
						(arc
							(start -0.1016 -0.1778)
							(mid -0.137521 -0.162921)
							(end -0.1524 -0.127)
						)
						(arc
							(start -0.1524 0.127)
							(mid -0.137521 0.162921)
							(end -0.1016 0.1778)
						)
						(arc
							(start 0.1016 0.1778)
							(mid 0.137521 0.162921)
							(end 0.1524 0.127)
						)
					)
					(width 0)
					(fill yes)
				)
			)
		)
	)
	(footprint ""
		(layer "F.Cu")
		(at 90.91549 -118.9863 90)
		(property "Reference" "SR742"
			(at 0 0 90)
			(layer "F.SilkS")
			(hide yes)
			(effects
				(font
					(size 1.27 1.27)
				)
			)
		)
		(property "Value" "2K2R2F-GP"
			(at 0.064008 -3.993896 90)
			(unlocked yes)
			(layer "F.Fab")
			(hide yes)
			(effects
				(font
					(size 1.016 1.016)
					(thickness 0.1524)
				)
			)
		)
		(property "Device Type" "R402H16"
			(at 0.064008 -5.517896 90)
			(unlocked yes)
			(layer "F.Fab")
			(hide yes)
			(effects
				(font
					(size 1.016 1.016)
					(thickness 0.1524)
				)
			)
		)
		(duplicate_pad_numbers_are_jumpers no)
		(fp_line
			(start 0.508 -0.9398)
			(end -0.508 -0.9398)
			(stroke
				(width 0.1524)
				(type default)
			)
			(layer "F.SilkS")
		)
		(fp_line
			(start -0.508 -0.9398)
			(end -0.508 0.9398)
			(stroke
				(width 0.1524)
				(type default)
			)
			(layer "F.SilkS")
		)
		(fp_rect
			(start -0.508 0.9398)
			(end 0.508 -0.9398)
			(stroke
				(width 0)
				(type default)
			)
			(fill no)
			(layer "F.CrtYd")
		)
		(fp_rect
			(start -0.508 0.9398)
			(end 0.508 -0.9398)
			(stroke
				(width 0)
				(type default)
			)
			(fill no)
			(layer "F.Fab")
		)
		(pad "1" smd custom
			(at 0 -0.4445 90)
			(size 0.1397 0.1397)
			(layers "F.Cu" "F.Mask" "F.Paste")
			(net "EXP_I2C_SCL_1")
			(options
				(clearance outline)
				(anchor circle)
			)
			(primitives
				(gr_poly
					(pts
						(arc
							(start -0.1778 -0.2794)
							(mid -0.249642 -0.249642)
							(end -0.2794 -0.1778)
						)
						(arc
							(start -0.2794 0.1778)
							(mid -0.249642 0.249642)
							(end -0.1778 0.2794)
						)
						(arc
							(start 0.1778 0.2794)
							(mid 0.249642 0.249642)
							(end 0.2794 0.1778)
						)
						(arc
							(start 0.2794 -0.1778)
							(mid 0.249642 -0.249642)
							(end 0.1778 -0.2794)
						)
					)
					(width 0)
					(fill yes)
				)
			)
		)
		(pad "2" smd custom
			(at 0 0.4445 90)
			(size 0.1397 0.1397)
			(layers "F.Cu" "F.Mask" "F.Paste")
			(net "P1V8_E")
			(options
				(clearance outline)
				(anchor circle)
			)
			(primitives
				(gr_poly
					(pts
						(arc
							(start -0.1778 -0.2794)
							(mid -0.249642 -0.249642)
							(end -0.2794 -0.1778)
						)
						(arc
							(start -0.2794 0.1778)
							(mid -0.249642 0.249642)
							(end -0.1778 0.2794)
						)
						(arc
							(start 0.1778 0.2794)
							(mid 0.249642 0.249642)
							(end 0.2794 0.1778)
						)
						(arc
							(start 0.2794 -0.1778)
							(mid 0.249642 -0.249642)
							(end 0.1778 -0.2794)
						)
					)
					(width 0)
					(fill yes)
				)
			)
		)
	)
	(footprint ""
		(layer "F.Cu")
		(at 286.385 -70.612 -90)
		(property "Reference" "R488"
			(at 0 0 270)
			(layer "F.SilkS")
			(hide yes)
			(effects
				(font
					(size 1.27 1.27)
				)
			)
		)
		(property "Value" "4K7R2F-GP"
			(at 0.064008 -3.993896 270)
			(unlocked yes)
			(layer "F.Fab")
			(hide yes)
			(effects
				(font
					(size 1.016 1.016)
					(thickness 0.1524)
				)
			)
		)
		(property "Device Type" "R402H16"
			(at 0.064008 -5.517896 270)
			(unlocked yes)
			(layer "F.Fab")
			(hide yes)
			(effects
				(font
					(size 1.016 1.016)
					(thickness 0.1524)
				)
			)
		)
		(duplicate_pad_numbers_are_jumpers no)
		(fp_line
			(start -0.508 -0.9398)
			(end -0.508 0.9398)
			(stroke
				(width 0.1524)
				(type default)
			)
			(layer "F.SilkS")
		)
		(fp_line
			(start 0.508 -0.9398)
			(end -0.508 -0.9398)
			(stroke
				(width 0.1524)
				(type default)
			)
			(layer "F.SilkS")
		)
		(fp_rect
			(start -0.508 0.9398)
			(end 0.508 -0.9398)
			(stroke
				(width 0)
				(type default)
			)
			(fill no)
			(layer "F.CrtYd")
		)
		(fp_rect
			(start -0.508 0.9398)
			(end 0.508 -0.9398)
			(stroke
				(width 0)
				(type default)
			)
			(fill no)
			(layer "F.Fab")
		)
		(pad "1" smd custom
			(at 0 -0.4445 270)
			(size 0.1397 0.1397)
			(layers "F.Cu" "F.Mask" "F.Paste")
			(net "P3V3_STBY")
			(options
				(clearance outline)
				(anchor circle)
			)
			(primitives
				(gr_poly
					(pts
						(arc
							(start -0.1778 -0.2794)
							(mid -0.249642 -0.249642)
							(end -0.2794 -0.1778)
						)
						(arc
							(start -0.2794 0.1778)
							(mid -0.249642 0.249642)
							(end -0.1778 0.2794)
						)
						(arc
							(start 0.1778 0.2794)
							(mid 0.249642 0.249642)
							(end 0.2794 0.1778)
						)
						(arc
							(start 0.2794 -0.1778)
							(mid 0.249642 -0.249642)
							(end 0.1778 -0.2794)
						)
					)
					(width 0)
					(fill yes)
				)
			)
		)
		(pad "2" smd custom
			(at 0 0.4445 270)
			(size 0.1397 0.1397)
			(layers "F.Cu" "F.Mask" "F.Paste")
			(net "HSC_MSB_ALERT_N")
			(options
				(clearance outline)
				(anchor circle)
			)
			(primitives
				(gr_poly
					(pts
						(arc
							(start -0.1778 -0.2794)
							(mid -0.249642 -0.249642)
							(end -0.2794 -0.1778)
						)
						(arc
							(start -0.2794 0.1778)
							(mid -0.249642 0.249642)
							(end -0.1778 0.2794)
						)
						(arc
							(start 0.1778 0.2794)
							(mid 0.249642 0.249642)
							(end 0.2794 0.1778)
						)
						(arc
							(start 0.2794 -0.1778)
							(mid 0.249642 -0.249642)
							(end 0.1778 -0.2794)
						)
					)
					(width 0)
					(fill yes)
				)
			)
		)
	)
	(footprint ""
		(layer "F.Cu")
		(at 132.08 -37.846)
		(property "Reference" "SLED25"
			(at 0 0 0)
			(layer "F.SilkS")
			(hide yes)
			(effects
				(font
					(size 1.27 1.27)
				)
			)
		)
		(property "Value" "LED-YG-51-GP"
			(at -2.6924 -1.4224 0)
			(unlocked yes)
			(layer "F.Fab")
			(hide yes)
			(effects
				(font
					(size 1.016 1.016)
					(thickness 0.1524)
				)
			)
		)
		(property "Device Type" "LED1608AKH40"
			(at -2.6924 -2.9464 0)
			(unlocked yes)
			(layer "F.Fab")
			(hide yes)
			(effects
				(font
					(size 1.016 1.016)
					(thickness 0.1524)
				)
			)
		)
		(duplicate_pad_numbers_are_jumpers no)
		(fp_line
			(start -0.7493 1.651)
			(end -0.7493 1.1811)
			(stroke
				(width 0.3302)
				(type default)
			)
			(layer "F.SilkS")
		)
		(fp_line
			(start -0.6604 -1.3716)
			(end 0.6604 -1.3716)
			(stroke
				(width 0.1524)
				(type default)
			)
			(layer "F.SilkS")
		)
		(fp_line
			(start -0.6604 1.3716)
			(end -0.6604 -1.3716)
			(stroke
				(width 0.1524)
				(type default)
			)
			(layer "F.SilkS")
		)
		(fp_line
			(start -0.5969 1.5494)
			(end 0.5842 1.5494)
			(stroke
				(width 0.508)
				(type default)
			)
			(layer "F.SilkS")
		)
		(fp_line
			(start 0.6604 -1.3716)
			(end 0.6604 1.3716)
			(stroke
				(width 0.1524)
				(type default)
			)
			(layer "F.SilkS")
		)
		(fp_line
			(start 0.6604 1.3716)
			(end -0.6604 1.3716)
			(stroke
				(width 0.1524)
				(type default)
			)
			(layer "F.SilkS")
		)
		(fp_line
			(start 0.7493 1.651)
			(end 0.7493 1.1811)
			(stroke
				(width 0.3302)
				(type default)
			)
			(layer "F.SilkS")
		)
		(fp_rect
			(start -0.6223 1.3335)
			(end 0.6223 -1.3335)
			(stroke
				(width 0)
				(type default)
			)
			(fill no)
			(layer "F.CrtYd")
		)
		(fp_rect
			(start -0.6223 1.3335)
			(end 0.6223 -1.3335)
			(stroke
				(width 0)
				(type default)
			)
			(fill no)
			(layer "F.Fab")
		)
		(pad "A" smd custom
			(at 0 -0.762)
			(size 0.2159 0.2159)
			(layers "F.Cu" "F.Mask" "F.Paste")
			(net "SYS_HB_LED_R")
			(options
				(clearance outline)
				(anchor circle)
			)
			(primitives
				(gr_poly
					(pts
						(arc
							(start -0.3302 -0.4318)
							(mid -0.402042 -0.402042)
							(end -0.4318 -0.3302)
						)
						(arc
							(start -0.4318 0.3302)
							(mid -0.402042 0.402042)
							(end -0.3302 0.4318)
						)
						(arc
							(start 0.3302 0.4318)
							(mid 0.402042 0.402042)
							(end 0.4318 0.3302)
						)
						(arc
							(start 0.4318 -0.3302)
							(mid 0.402042 -0.402042)
							(end 0.3302 -0.4318)
						)
					)
					(width 0)
					(fill yes)
				)
			)
		)
		(pad "K" smd custom
			(at 0 0.762)
			(size 0.2159 0.2159)
			(layers "F.Cu" "F.Mask" "F.Paste")
			(net "SYS_HB_LED_D")
			(options
				(clearance outline)
				(anchor circle)
			)
			(primitives
				(gr_poly
					(pts
						(arc
							(start -0.3302 -0.4318)
							(mid -0.402042 -0.402042)
							(end -0.4318 -0.3302)
						)
						(arc
							(start -0.4318 0.3302)
							(mid -0.402042 0.402042)
							(end -0.3302 0.4318)
						)
						(arc
							(start 0.3302 0.4318)
							(mid 0.402042 0.402042)
							(end 0.4318 0.3302)
						)
						(arc
							(start 0.4318 -0.3302)
							(mid 0.402042 -0.402042)
							(end 0.3302 -0.4318)
						)
					)
					(width 0)
					(fill yes)
				)
			)
		)
	)
	(footprint ""
		(layer "F.Cu")
		(at 82.555842 -139.771882 180)
		(property "Reference" "SC1121"
			(at 0 0 180)
			(layer "F.SilkS")
			(hide yes)
			(effects
				(font
					(size 1.27 1.27)
				)
			)
		)
		(property "Value" "SCD1U16V2KX-3GP"
			(at 1.1811 -2.7051 180)
			(unlocked yes)
			(layer "F.Fab")
			(hide yes)
			(effects
				(font
					(size 1.016 1.016)
					(thickness 0.1524)
				)
			)
		)
		(property "Device Type" "C402H22"
			(at 1.1811 -4.2291 180)
			(unlocked yes)
			(layer "F.Fab")
			(hide yes)
			(effects
				(font
					(size 1.016 1.016)
					(thickness 0.1524)
				)
			)
		)
		(duplicate_pad_numbers_are_jumpers no)
		(fp_rect
			(start -0.4318 0.9525)
			(end 0.4318 -0.9525)
			(stroke
				(width 0)
				(type default)
			)
			(fill no)
			(layer "F.CrtYd")
		)
		(fp_rect
			(start -0.4318 0.9525)
			(end 0.4318 -0.9525)
			(stroke
				(width 0)
				(type default)
			)
			(fill no)
			(layer "F.Fab")
		)
		(pad "1" smd custom
			(at 0 -0.4445 180)
			(size 0.1524 0.1524)
			(layers "F.Cu" "F.Mask" "F.Paste")
			(net "P3V3_STBY")
			(options
				(clearance outline)
				(anchor circle)
			)
			(primitives
				(gr_poly
					(pts
						(arc
							(start 0.3048 -0.2032)
							(mid 0.275042 -0.275042)
							(end 0.2032 -0.3048)
						)
						(arc
							(start -0.2032 -0.3048)
							(mid -0.275042 -0.275042)
							(end -0.3048 -0.2032)
						)
						(arc
							(start -0.3048 0.2032)
							(mid -0.275042 0.275042)
							(end -0.2032 0.3048)
						)
						(arc
							(start 0.2032 0.3048)
							(mid 0.275042 0.275042)
							(end 0.3048 0.2032)
						)
					)
					(width 0)
					(fill yes)
				)
			)
		)
		(pad "2" smd custom
			(at 0 0.4445 180)
			(size 0.1524 0.1524)
			(layers "F.Cu" "F.Mask" "F.Paste")
			(net "GND")
			(options
				(clearance outline)
				(anchor circle)
			)
			(primitives
				(gr_poly
					(pts
						(arc
							(start 0.3048 -0.2032)
							(mid 0.275042 -0.275042)
							(end 0.2032 -0.3048)
						)
						(arc
							(start -0.2032 -0.3048)
							(mid -0.275042 -0.275042)
							(end -0.3048 -0.2032)
						)
						(arc
							(start -0.3048 0.2032)
							(mid -0.275042 0.275042)
							(end -0.2032 0.3048)
						)
						(arc
							(start 0.2032 0.3048)
							(mid 0.275042 0.275042)
							(end 0.3048 0.2032)
						)
					)
					(width 0)
					(fill yes)
				)
			)
		)
	)
	(footprint ""
		(layer "F.Cu")
		(at 261.366 -39.37 90)
		(property "Reference" "PG4"
			(at 0 0 90)
			(layer "F.SilkS")
			(hide yes)
			(effects
				(font
					(size 1.27 1.27)
				)
			)
		)
		(property "Value" "COPPER-CLOSE-GP-U"
			(at 0.0762 -2.8702 90)
			(unlocked yes)
			(layer "F.Fab")
			(hide yes)
			(effects
				(font
					(size 1.016 1.016)
					(thickness 0.1524)
				)
			)
		)
		(property "Device Type" "CON2C-U"
			(at 0.0762 -4.3942 90)
			(unlocked yes)
			(layer "F.Fab")
			(hide yes)
			(effects
				(font
					(size 1.016 1.016)
					(thickness 0.1524)
				)
			)
		)
		(duplicate_pad_numbers_are_jumpers no)
		(fp_rect
			(start -0.9398 0.9652)
			(end 0.9398 -0.9652)
			(stroke
				(width 0)
				(type default)
			)
			(fill no)
			(layer "F.CrtYd")
		)
		(fp_rect
			(start -0.9398 0.9652)
			(end 0.9398 -0.9652)
			(stroke
				(width 0)
				(type default)
			)
			(fill no)
			(layer "F.Fab")
		)
		(pad "1" smd custom
			(at 0 -0.5334 90)
			(size 0.17145 0.17145)
			(layers "F.Cu" "F.Mask" "F.Paste")
			(net "AGND_P1V8_STBY")
			(options
				(clearance outline)
				(anchor circle)
			)
			(primitives
				(gr_poly
					(pts
						(xy -0.127 0.3429) (xy -0.127 0.1651) (xy -0.635 -0.3429) (xy 0.635 -0.3429) (xy 0.127 0.1651)
						(xy 0.127 0.3429)
					)
					(width 0)
					(fill yes)
				)
			)
		)
		(pad "2" smd custom
			(at 0 0.5334 90)
			(size 0.17145 0.17145)
			(layers "F.Cu" "F.Mask" "F.Paste")
			(net "GND")
			(options
				(clearance outline)
				(anchor circle)
			)
			(primitives
				(gr_poly
					(pts
						(xy -0.635 0.3429) (xy -0.127 -0.1651) (xy -0.127 -0.3429) (xy 0.127 -0.3429) (xy 0.127 -0.1651)
						(xy 0.635 0.3429)
					)
					(width 0)
					(fill yes)
				)
			)
		)
	)
	(footprint ""
		(layer "F.Cu")
		(at 178.816 -225.171)
		(property "Reference" "R325"
			(at 0 0 0)
			(layer "F.SilkS")
			(hide yes)
			(effects
				(font
					(size 1.27 1.27)
				)
			)
		)
		(property "Value" "4K7R2F-GP"
			(at 0.064008 -3.993896 0)
			(unlocked yes)
			(layer "F.Fab")
			(hide yes)
			(effects
				(font
					(size 1.016 1.016)
					(thickness 0.1524)
				)
			)
		)
		(property "Device Type" "R402H16"
			(at 0.064008 -5.517896 0)
			(unlocked yes)
			(layer "F.Fab")
			(hide yes)
			(effects
				(font
					(size 1.016 1.016)
					(thickness 0.1524)
				)
			)
		)
		(duplicate_pad_numbers_are_jumpers no)
		(fp_line
			(start -0.508 -0.9398)
			(end -0.508 0.9398)
			(stroke
				(width 0.1524)
				(type default)
			)
			(layer "F.SilkS")
		)
		(fp_line
			(start 0.508 -0.9398)
			(end -0.508 -0.9398)
			(stroke
				(width 0.1524)
				(type default)
			)
			(layer "F.SilkS")
		)
		(fp_rect
			(start -0.508 0.9398)
			(end 0.508 -0.9398)
			(stroke
				(width 0)
				(type default)
			)
			(fill no)
			(layer "F.CrtYd")
		)
		(fp_rect
			(start -0.508 0.9398)
			(end 0.508 -0.9398)
			(stroke
				(width 0)
				(type default)
			)
			(fill no)
			(layer "F.Fab")
		)
		(pad "1" smd custom
			(at 0 -0.4445)
			(size 0.1397 0.1397)
			(layers "F.Cu" "F.Mask" "F.Paste")
			(net "P3V3_STBY")
			(options
				(clearance outline)
				(anchor circle)
			)
			(primitives
				(gr_poly
					(pts
						(arc
							(start -0.1778 -0.2794)
							(mid -0.249642 -0.249642)
							(end -0.2794 -0.1778)
						)
						(arc
							(start -0.2794 0.1778)
							(mid -0.249642 0.249642)
							(end -0.1778 0.2794)
						)
						(arc
							(start 0.1778 0.2794)
							(mid 0.249642 0.249642)
							(end 0.2794 0.1778)
						)
						(arc
							(start 0.2794 -0.1778)
							(mid 0.249642 -0.249642)
							(end 0.1778 -0.2794)
						)
					)
					(width 0)
					(fill yes)
				)
			)
		)
		(pad "2" smd custom
			(at 0 0.4445)
			(size 0.1397 0.1397)
			(layers "F.Cu" "F.Mask" "F.Paste")
			(net "BMC_PWRBTN_N")
			(options
				(clearance outline)
				(anchor circle)
			)
			(primitives
				(gr_poly
					(pts
						(arc
							(start -0.1778 -0.2794)
							(mid -0.249642 -0.249642)
							(end -0.2794 -0.1778)
						)
						(arc
							(start -0.2794 0.1778)
							(mid -0.249642 0.249642)
							(end -0.1778 0.2794)
						)
						(arc
							(start 0.1778 0.2794)
							(mid 0.249642 0.249642)
							(end 0.2794 0.1778)
						)
						(arc
							(start 0.2794 -0.1778)
							(mid 0.249642 -0.249642)
							(end 0.1778 -0.2794)
						)
					)
					(width 0)
					(fill yes)
				)
			)
		)
	)
)
